(kicad_pcb
	(version 20260206)
	(generator "pcbnew")
	(generator_version "10.0")
	(general
		(thickness 1.6)
		(legacy_teardrops no)
	)
	(paper "A4")
	(title_block
		(title "01162023_DA0F0TEBIF0_F0T_Expander_BD_F_brd_V02_OCP.brd")
		(comment 1 "Grand Teton / footprints 1022-1028 of 9728")
	)
	(layers
		(0 "F.Cu" signal "TOP")
		(4 "In1.Cu" signal "GND")
		(6 "In2.Cu" signal "VCC")
		(8 "In3.Cu" signal "VCC1")
		(10 "In4.Cu" signal "GND1")
		(12 "In5.Cu" signal "IN1")
		(14 "In6.Cu" signal "GND2")
		(16 "In7.Cu" signal "IN2")
		(18 "In8.Cu" signal "GND3")
		(20 "In9.Cu" signal "IN3")
		(22 "In10.Cu" signal "GND4")
		(24 "In11.Cu" signal "IN4")
		(26 "In12.Cu" signal "GND5")
		(28 "In13.Cu" signal "IN5")
		(30 "In14.Cu" signal "GND6")
		(32 "In15.Cu" signal "IN6")
		(34 "In16.Cu" signal "GND7")
		(2 "B.Cu" signal "BOTTOM")
		(9 "F.Adhes" user "F.Adhesive")
		(11 "B.Adhes" user "B.Adhesive")
		(13 "F.Paste" user "Package Geometry/Pastemask Top")
		(15 "B.Paste" user "Package Geometry/Pastemask Bottom")
		(5 "F.SilkS" user "Ref Des/Silkscreen Top")
		(7 "B.SilkS" user "Ref Des/Silkscreen Bottom")
		(1 "F.Mask" user "Board Geometry/Soldermask Top")
		(3 "B.Mask" user "Board Geometry/Soldermask Bottom")
		(17 "Dwgs.User" user "User.Drawings")
		(19 "Cmts.User" user "User.Comments")
		(21 "Eco1.User" user "User.Eco1")
		(23 "Eco2.User" user "User.Eco2")
		(25 "Edge.Cuts" user "Board Geometry/Outline")
		(27 "Margin" user)
		(31 "F.CrtYd" user "Package Geometry/Place Bound Top")
		(29 "B.CrtYd" user "Package Geometry/Place Bound Bottom")
		(35 "F.Fab" user "Ref Des/Assembly Top")
		(33 "B.Fab" user "Ref Des/Assembly Bottom")
	)
	(footprint ""
		(layer "F.Cu")
		(at 442.794136 -115.394486)
		(property "Reference" "PR7106"
			(at 0 0 0)
			(layer "F.SilkS")
			(hide yes)
			(effects
				(font
					(size 1.27 1.27)
				)
			)
		)
		(property "Value" ""
			(at 0 0 0)
			(layer "F.Fab")
			(effects
				(font
					(size 1.27 1.27)
				)
			)
		)
		(duplicate_pad_numbers_are_jumpers no)
		(fp_line
			(start -0.7874 -0.4064)
			(end 0.7874 -0.4064)
			(stroke
				(width 0.1524)
				(type default)
			)
			(layer "F.SilkS")
		)
		(fp_line
			(start -0.7874 0.4064)
			(end -0.7874 -0.4064)
			(stroke
				(width 0.1524)
				(type default)
			)
			(layer "F.SilkS")
		)
		(fp_line
			(start 0.7874 -0.4064)
			(end 0.7874 0.4064)
			(stroke
				(width 0.1524)
				(type default)
			)
			(layer "F.SilkS")
		)
		(fp_line
			(start 0.7874 0.4064)
			(end -0.7874 0.4064)
			(stroke
				(width 0.1524)
				(type default)
			)
			(layer "F.SilkS")
		)
		(fp_line
			(start -0.67945 -0.305054)
			(end -0.12065 -0.305054)
			(stroke
				(width 0.1)
				(type default)
			)
			(layer "F.Fab")
		)
		(fp_line
			(start -0.67945 0.3048)
			(end -0.67945 -0.305054)
			(stroke
				(width 0.1)
				(type default)
			)
			(layer "F.Fab")
		)
		(fp_line
			(start -0.12065 -0.305054)
			(end -0.12065 -0.2794)
			(stroke
				(width 0.1)
				(type default)
			)
			(layer "F.Fab")
		)
		(fp_line
			(start -0.12065 -0.2794)
			(end 0.12065 -0.2794)
			(stroke
				(width 0.1)
				(type default)
			)
			(layer "F.Fab")
		)
		(fp_line
			(start -0.12065 0.2794)
			(end -0.12065 0.3048)
			(stroke
				(width 0.1)
				(type default)
			)
			(layer "F.Fab")
		)
		(fp_line
			(start -0.12065 0.3048)
			(end -0.67945 0.3048)
			(stroke
				(width 0.1)
				(type default)
			)
			(layer "F.Fab")
		)
		(fp_line
			(start 0.120396 0.2794)
			(end -0.12065 0.2794)
			(stroke
				(width 0.1)
				(type default)
			)
			(layer "F.Fab")
		)
		(fp_line
			(start 0.120396 0.3048)
			(end 0.120396 0.2794)
			(stroke
				(width 0.1)
				(type default)
			)
			(layer "F.Fab")
		)
		(fp_line
			(start 0.12065 -0.3048)
			(end 0.67945 -0.3048)
			(stroke
				(width 0.1)
				(type default)
			)
			(layer "F.Fab")
		)
		(fp_line
			(start 0.12065 -0.2794)
			(end 0.12065 -0.3048)
			(stroke
				(width 0.1)
				(type default)
			)
			(layer "F.Fab")
		)
		(fp_line
			(start 0.67945 -0.3048)
			(end 0.67945 0.3048)
			(stroke
				(width 0.1)
				(type default)
			)
			(layer "F.Fab")
		)
		(fp_line
			(start 0.67945 0.3048)
			(end 0.120396 0.3048)
			(stroke
				(width 0.1)
				(type default)
			)
			(layer "F.Fab")
		)
		(pad "1" smd circle
			(at -0.40005 0)
			(size 0 0)
			(layers "F.Cu" "F.Mask" "F.Paste")
			(net "P3V3_NIC7_CO_ILIMIT")
		)
		(pad "2" smd circle
			(at 0.40005 0)
			(size 0 0)
			(layers "F.Cu" "F.Mask" "F.Paste")
			(net "GND")
		)
	)
	(footprint ""
		(layer "F.Cu")
		(at 155.380436 -106.488738)
		(property "Reference" "C266"
			(at 0 0 0)
			(layer "F.SilkS")
			(hide yes)
			(effects
				(font
					(size 1.27 1.27)
				)
			)
		)
		(property "Value" ""
			(at 0 0 0)
			(layer "F.Fab")
			(effects
				(font
					(size 1.27 1.27)
				)
			)
		)
		(duplicate_pad_numbers_are_jumpers no)
		(fp_line
			(start -0.299974 -0.150114)
			(end 0.299974 -0.150114)
			(stroke
				(width 0.1)
				(type default)
			)
			(layer "F.Fab")
		)
		(fp_line
			(start -0.299974 0.150114)
			(end -0.299974 -0.150114)
			(stroke
				(width 0.1)
				(type default)
			)
			(layer "F.Fab")
		)
		(fp_line
			(start 0.299974 -0.150114)
			(end 0.299974 0.150114)
			(stroke
				(width 0.1)
				(type default)
			)
			(layer "F.Fab")
		)
		(fp_line
			(start 0.299974 0.150114)
			(end -0.299974 0.150114)
			(stroke
				(width 0.1)
				(type default)
			)
			(layer "F.Fab")
		)
		(pad "1" smd rect
			(at -0.2667 0)
			(size 0.3048 0.381)
			(layers "F.Cu" "F.Mask" "F.Paste")
			(net "P5E_PEX1_STN1_TX_DP<20>")
		)
		(pad "2" smd rect
			(at 0.2667 0)
			(size 0.3048 0.381)
			(layers "F.Cu" "F.Mask" "F.Paste")
			(net "P5E_PEX1_STN1_TX_C_DP<20>")
		)
	)
	(footprint ""
		(layer "F.Cu")
		(at 136.355328 -35.876738)
		(property "Reference" "R6057"
			(at 0 0 0)
			(layer "F.SilkS")
			(hide yes)
			(effects
				(font
					(size 1.27 1.27)
				)
			)
		)
		(property "Value" ""
			(at 0 0 0)
			(layer "F.Fab")
			(effects
				(font
					(size 1.27 1.27)
				)
			)
		)
		(duplicate_pad_numbers_are_jumpers no)
		(fp_line
			(start -0.7874 -0.4064)
			(end 0.7874 -0.4064)
			(stroke
				(width 0.1524)
				(type default)
			)
			(layer "F.SilkS")
		)
		(fp_line
			(start -0.7874 0.4064)
			(end -0.7874 -0.4064)
			(stroke
				(width 0.1524)
				(type default)
			)
			(layer "F.SilkS")
		)
		(fp_line
			(start 0.7874 -0.4064)
			(end 0.7874 0.4064)
			(stroke
				(width 0.1524)
				(type default)
			)
			(layer "F.SilkS")
		)
		(fp_line
			(start 0.7874 0.4064)
			(end -0.7874 0.4064)
			(stroke
				(width 0.1524)
				(type default)
			)
			(layer "F.SilkS")
		)
		(fp_line
			(start -0.67945 -0.305054)
			(end -0.12065 -0.305054)
			(stroke
				(width 0.1)
				(type default)
			)
			(layer "F.Fab")
		)
		(fp_line
			(start -0.67945 0.3048)
			(end -0.67945 -0.305054)
			(stroke
				(width 0.1)
				(type default)
			)
			(layer "F.Fab")
		)
		(fp_line
			(start -0.12065 -0.305054)
			(end -0.12065 -0.2794)
			(stroke
				(width 0.1)
				(type default)
			)
			(layer "F.Fab")
		)
		(fp_line
			(start -0.12065 -0.2794)
			(end 0.12065 -0.2794)
			(stroke
				(width 0.1)
				(type default)
			)
			(layer "F.Fab")
		)
		(fp_line
			(start -0.12065 0.2794)
			(end -0.12065 0.3048)
			(stroke
				(width 0.1)
				(type default)
			)
			(layer "F.Fab")
		)
		(fp_line
			(start -0.12065 0.3048)
			(end -0.67945 0.3048)
			(stroke
				(width 0.1)
				(type default)
			)
			(layer "F.Fab")
		)
		(fp_line
			(start 0.120396 0.2794)
			(end -0.12065 0.2794)
			(stroke
				(width 0.1)
				(type default)
			)
			(layer "F.Fab")
		)
		(fp_line
			(start 0.120396 0.3048)
			(end 0.120396 0.2794)
			(stroke
				(width 0.1)
				(type default)
			)
			(layer "F.Fab")
		)
		(fp_line
			(start 0.12065 -0.3048)
			(end 0.67945 -0.3048)
			(stroke
				(width 0.1)
				(type default)
			)
			(layer "F.Fab")
		)
		(fp_line
			(start 0.12065 -0.2794)
			(end 0.12065 -0.3048)
			(stroke
				(width 0.1)
				(type default)
			)
			(layer "F.Fab")
		)
		(fp_line
			(start 0.67945 -0.3048)
			(end 0.67945 0.3048)
			(stroke
				(width 0.1)
				(type default)
			)
			(layer "F.Fab")
		)
		(fp_line
			(start 0.67945 0.3048)
			(end 0.120396 0.3048)
			(stroke
				(width 0.1)
				(type default)
			)
			(layer "F.Fab")
		)
		(pad "1" smd circle
			(at -0.40005 0)
			(size 0 0)
			(layers "F.Cu" "F.Mask" "F.Paste")
			(net "P3V3_AUX")
		)
		(pad "2" smd circle
			(at 0.40005 0)
			(size 0 0)
			(layers "F.Cu" "F.Mask" "F.Paste")
			(net "PWRGD_P3V3_SSD5_D")
		)
	)
	(footprint ""
		(layer "F.Cu")
		(at 406.50414 -370.794026 -90)
		(property "Reference" "Q242"
			(at 0.686308 -3.06832 0)
			(unlocked yes)
			(layer "F.SilkS")
			(effects
				(font
					(size 0.7874 0.5842)
					(thickness 0.1524)
				)
			)
		)
		(property "Value" ""
			(at 0 0 270)
			(layer "F.Fab")
			(effects
				(font
					(size 1.27 1.27)
				)
			)
		)
		(duplicate_pad_numbers_are_jumpers no)
		(fp_line
			(start -1.376172 1.199896)
			(end -1.376172 -1.199896)
			(stroke
				(width 0.1524)
				(type default)
			)
			(layer "F.SilkS")
		)
		(fp_line
			(start 1.376172 1.199896)
			(end -1.376172 1.199896)
			(stroke
				(width 0.1524)
				(type default)
			)
			(layer "F.SilkS")
		)
		(fp_line
			(start 0 -0.762)
			(end 0.508 -1.199896)
			(stroke
				(width 0.1524)
				(type default)
			)
			(layer "F.SilkS")
		)
		(fp_line
			(start -1.376172 -1.199896)
			(end -0.508 -1.199896)
			(stroke
				(width 0.1524)
				(type default)
			)
			(layer "F.SilkS")
		)
		(fp_line
			(start -0.508 -1.199896)
			(end 0 -0.762)
			(stroke
				(width 0.1524)
				(type default)
			)
			(layer "F.SilkS")
		)
		(fp_line
			(start 0.508 -1.199896)
			(end 1.376172 -1.199896)
			(stroke
				(width 0.1524)
				(type default)
			)
			(layer "F.SilkS")
		)
		(fp_line
			(start 1.376172 -1.199896)
			(end 1.376172 1.199896)
			(stroke
				(width 0.1524)
				(type default)
			)
			(layer "F.SilkS")
		)
		(fp_poly
			(pts
				(xy -0.982726 -1.440434) (xy -0.601726 -2.202434) (xy -1.363726 -2.202434)
			)
			(stroke
				(width 0)
				(type default)
			)
			(fill yes)
			(layer "F.SilkS")
		)
		(fp_line
			(start -0.674878 1.100074)
			(end -0.674878 -1.100074)
			(stroke
				(width 0.1)
				(type default)
			)
			(layer "F.Fab")
		)
		(fp_line
			(start 0.674878 1.100074)
			(end -0.674878 1.100074)
			(stroke
				(width 0.1)
				(type default)
			)
			(layer "F.Fab")
		)
		(fp_line
			(start -0.674878 -1.100074)
			(end 0.674878 -1.100074)
			(stroke
				(width 0.1)
				(type default)
			)
			(layer "F.Fab")
		)
		(fp_line
			(start 0.674878 -1.100074)
			(end 0.674878 1.100074)
			(stroke
				(width 0.1)
				(type default)
			)
			(layer "F.Fab")
		)
		(fp_poly
			(pts
				(xy -1.4605 -0.7493) (xy -2.2225 -1.1303) (xy -2.2225 -0.3683)
			)
			(stroke
				(width 0)
				(type default)
			)
			(fill yes)
			(layer "F.Fab")
		)
		(pad "1" smd rect
			(at -0.899922 -0.750062 180)
			(size 0.6096 0.6096)
			(layers "F.Cu" "F.Mask" "F.Paste")
			(net "GND")
		)
		(pad "2" smd rect
			(at -0.899922 0 180)
			(size 0.4064 0.6096)
			(layers "F.Cu" "F.Mask" "F.Paste")
			(net "GPU_3V3IO_RSVD4")
		)
		(pad "3" smd rect
			(at -0.899922 0.750062 180)
			(size 0.6096 0.6096)
			(layers "F.Cu" "F.Mask" "F.Paste")
			(net "GPU_3V3IO_RSVD4_ISO")
		)
		(pad "4" smd rect
			(at 0.899922 0.750062 180)
			(size 0.6096 0.6096)
			(layers "F.Cu" "F.Mask" "F.Paste")
			(net "GND")
		)
		(pad "5" smd rect
			(at 0.899922 0 180)
			(size 0.4064 0.6096)
			(layers "F.Cu" "F.Mask" "F.Paste")
			(net "GPU_3V3IO_RSVD4_N")
		)
		(pad "6" smd rect
			(at 0.899922 -0.750062 180)
			(size 0.6096 0.6096)
			(layers "F.Cu" "F.Mask" "F.Paste")
			(net "GPU_3V3IO_RSVD4_N")
		)
	)
	(footprint ""
		(layer "F.Cu")
		(at 242.310412 -125.979428)
		(property "Reference" "R879"
			(at 0 0 0)
			(layer "F.SilkS")
			(hide yes)
			(effects
				(font
					(size 1.27 1.27)
				)
			)
		)
		(property "Value" ""
			(at 0 0 0)
			(layer "F.Fab")
			(effects
				(font
					(size 1.27 1.27)
				)
			)
		)
		(duplicate_pad_numbers_are_jumpers no)
		(fp_line
			(start -0.7874 -0.4064)
			(end 0.7874 -0.4064)
			(stroke
				(width 0.1524)
				(type default)
			)
			(layer "F.SilkS")
		)
		(fp_line
			(start -0.7874 0.4064)
			(end -0.7874 -0.4064)
			(stroke
				(width 0.1524)
				(type default)
			)
			(layer "F.SilkS")
		)
		(fp_line
			(start 0.7874 -0.4064)
			(end 0.7874 0.4064)
			(stroke
				(width 0.1524)
				(type default)
			)
			(layer "F.SilkS")
		)
		(fp_line
			(start 0.7874 0.4064)
			(end -0.7874 0.4064)
			(stroke
				(width 0.1524)
				(type default)
			)
			(layer "F.SilkS")
		)
		(fp_line
			(start -0.67945 -0.305054)
			(end -0.12065 -0.305054)
			(stroke
				(width 0.1)
				(type default)
			)
			(layer "F.Fab")
		)
		(fp_line
			(start -0.67945 0.3048)
			(end -0.67945 -0.305054)
			(stroke
				(width 0.1)
				(type default)
			)
			(layer "F.Fab")
		)
		(fp_line
			(start -0.12065 -0.305054)
			(end -0.12065 -0.2794)
			(stroke
				(width 0.1)
				(type default)
			)
			(layer "F.Fab")
		)
		(fp_line
			(start -0.12065 -0.2794)
			(end 0.12065 -0.2794)
			(stroke
				(width 0.1)
				(type default)
			)
			(layer "F.Fab")
		)
		(fp_line
			(start -0.12065 0.2794)
			(end -0.12065 0.3048)
			(stroke
				(width 0.1)
				(type default)
			)
			(layer "F.Fab")
		)
		(fp_line
			(start -0.12065 0.3048)
			(end -0.67945 0.3048)
			(stroke
				(width 0.1)
				(type default)
			)
			(layer "F.Fab")
		)
		(fp_line
			(start 0.120396 0.2794)
			(end -0.12065 0.2794)
			(stroke
				(width 0.1)
				(type default)
			)
			(layer "F.Fab")
		)
		(fp_line
			(start 0.120396 0.3048)
			(end 0.120396 0.2794)
			(stroke
				(width 0.1)
				(type default)
			)
			(layer "F.Fab")
		)
		(fp_line
			(start 0.12065 -0.3048)
			(end 0.67945 -0.3048)
			(stroke
				(width 0.1)
				(type default)
			)
			(layer "F.Fab")
		)
		(fp_line
			(start 0.12065 -0.2794)
			(end 0.12065 -0.3048)
			(stroke
				(width 0.1)
				(type default)
			)
			(layer "F.Fab")
		)
		(fp_line
			(start 0.67945 -0.3048)
			(end 0.67945 0.3048)
			(stroke
				(width 0.1)
				(type default)
			)
			(layer "F.Fab")
		)
		(fp_line
			(start 0.67945 0.3048)
			(end 0.120396 0.3048)
			(stroke
				(width 0.1)
				(type default)
			)
			(layer "F.Fab")
		)
		(pad "1" smd circle
			(at -0.40005 0)
			(size 0 0)
			(layers "F.Cu" "F.Mask" "F.Paste")
			(net "P3V3_NIC4")
		)
		(pad "2" smd circle
			(at 0.40005 0)
			(size 0 0)
			(layers "F.Cu" "F.Mask" "F.Paste")
			(net "PWRGD_P3V3_NIC4")
		)
	)
	(footprint ""
		(layer "F.Cu")
		(at 34.851848 -343.952322 90)
		(property "Reference" "C177"
			(at 0 0 90)
			(layer "F.SilkS")
			(hide yes)
			(effects
				(font
					(size 1.27 1.27)
				)
			)
		)
		(property "Value" ""
			(at 0 0 90)
			(layer "F.Fab")
			(effects
				(font
					(size 1.27 1.27)
				)
			)
		)
		(duplicate_pad_numbers_are_jumpers no)
		(fp_line
			(start 0.299974 -0.150114)
			(end 0.299974 0.150114)
			(stroke
				(width 0.1)
				(type default)
			)
			(layer "F.Fab")
		)
		(fp_line
			(start -0.299974 -0.150114)
			(end 0.299974 -0.150114)
			(stroke
				(width 0.1)
				(type default)
			)
			(layer "F.Fab")
		)
		(fp_line
			(start 0.299974 0.150114)
			(end -0.299974 0.150114)
			(stroke
				(width 0.1)
				(type default)
			)
			(layer "F.Fab")
		)
		(fp_line
			(start -0.299974 0.150114)
			(end -0.299974 -0.150114)
			(stroke
				(width 0.1)
				(type default)
			)
			(layer "F.Fab")
		)
		(pad "1" smd rect
			(at -0.2667 0 90)
			(size 0.3048 0.381)
			(layers "F.Cu" "F.Mask" "F.Paste")
			(net "P5E_PEX0_STN7_TX_DP<119>")
		)
		(pad "2" smd rect
			(at 0.2667 0 90)
			(size 0.3048 0.381)
			(layers "F.Cu" "F.Mask" "F.Paste")
			(net "P5E_PEX0_STN7_TX_C_DP<119>")
		)
	)
	(footprint ""
		(layer "F.Cu")
		(at 116.684298 -29.222954 -90)
		(property "Reference" "PC918"
			(at 0 0 270)
			(layer "F.SilkS")
			(hide yes)
			(effects
				(font
					(size 1.27 1.27)
				)
			)
		)
		(property "Value" ""
			(at 0 0 270)
			(layer "F.Fab")
			(effects
				(font
					(size 1.27 1.27)
				)
			)
		)
		(duplicate_pad_numbers_are_jumpers no)
		(fp_line
			(start -0.7874 0.4064)
			(end -0.7874 -0.4064)
			(stroke
				(width 0.1524)
				(type default)
			)
			(layer "F.SilkS")
		)
		(fp_line
			(start 0.7874 0.4064)
			(end -0.7874 0.4064)
			(stroke
				(width 0.1524)
				(type default)
			)
			(layer "F.SilkS")
		)
		(fp_line
			(start -0.7874 -0.4064)
			(end 0.7874 -0.4064)
			(stroke
				(width 0.1524)
				(type default)
			)
			(layer "F.SilkS")
		)
		(fp_line
			(start 0.7874 -0.4064)
			(end 0.7874 0.4064)
			(stroke
				(width 0.1524)
				(type default)
			)
			(layer "F.SilkS")
		)
		(fp_line
			(start -0.67945 0.3048)
			(end -0.67945 -0.305054)
			(stroke
				(width 0.1)
				(type default)
			)
			(layer "F.Fab")
		)
		(fp_line
			(start -0.12065 0.3048)
			(end -0.67945 0.3048)
			(stroke
				(width 0.1)
				(type default)
			)
			(layer "F.Fab")
		)
		(fp_line
			(start 0.120396 0.3048)
			(end 0.120396 0.2794)
			(stroke
				(width 0.1)
				(type default)
			)
			(layer "F.Fab")
		)
		(fp_line
			(start 0.67945 0.3048)
			(end 0.120396 0.3048)
			(stroke
				(width 0.1)
				(type default)
			)
			(layer "F.Fab")
		)
		(fp_line
			(start -0.12065 0.2794)
			(end -0.12065 0.3048)
			(stroke
				(width 0.1)
				(type default)
			)
			(layer "F.Fab")
		)
		(fp_line
			(start 0.120396 0.2794)
			(end -0.12065 0.2794)
			(stroke
				(width 0.1)
				(type default)
			)
			(layer "F.Fab")
		)
		(fp_line
			(start -0.12065 -0.2794)
			(end 0.12065 -0.2794)
			(stroke
				(width 0.1)
				(type default)
			)
			(layer "F.Fab")
		)
		(fp_line
			(start 0.12065 -0.2794)
			(end 0.12065 -0.3048)
			(stroke
				(width 0.1)
				(type default)
			)
			(layer "F.Fab")
		)
		(fp_line
			(start 0.12065 -0.3048)
			(end 0.67945 -0.3048)
			(stroke
				(width 0.1)
				(type default)
			)
			(layer "F.Fab")
		)
		(fp_line
			(start 0.67945 -0.3048)
			(end 0.67945 0.3048)
			(stroke
				(width 0.1)
				(type default)
			)
			(layer "F.Fab")
		)
		(fp_line
			(start -0.67945 -0.305054)
			(end -0.12065 -0.305054)
			(stroke
				(width 0.1)
				(type default)
			)
			(layer "F.Fab")
		)
		(fp_line
			(start -0.12065 -0.305054)
			(end -0.12065 -0.2794)
			(stroke
				(width 0.1)
				(type default)
			)
			(layer "F.Fab")
		)
		(pad "1" smd circle
			(at -0.40005 0 270)
			(size 0 0)
			(layers "F.Cu" "F.Mask" "F.Paste")
			(net "P3V3_AUX")
		)
		(pad "2" smd circle
			(at 0.40005 0 270)
			(size 0 0)
			(layers "F.Cu" "F.Mask" "F.Paste")
			(net "GND")
		)
	)
)
